(kicad_pcb
	(version 20241229)
	(generator "pcbnew")
	(generator_version "9.0")
	(general
		(thickness 1.6642)
		(legacy_teardrops no)
	)
	(paper "A3")
	(title_block
		(title "PolarFire SoM")
		(date "2025-07-22")
		(rev "1.1.4")
		(company "Antmicro Ltd")
		(comment 1 "www.antmicro.com")
		(comment 9 "footprints 271-275 of 470")
	)
	(layers
		(0 "F.Cu" mixed)
		(4 "In1.Cu" power)
		(6 "In2.Cu" signal)
		(8 "In3.Cu" power)
		(10 "In4.Cu" signal)
		(12 "In5.Cu" power)
		(14 "In6.Cu" power)
		(16 "In7.Cu" signal)
		(18 "In8.Cu" power)
		(20 "In9.Cu" signal)
		(22 "In10.Cu" power)
		(24 "In11.Cu" signal)
		(26 "In12.Cu" signal)
		(2 "B.Cu" mixed)
		(9 "F.Adhes" user "F.Adhesive")
		(11 "B.Adhes" user "B.Adhesive")
		(13 "F.Paste" user)
		(15 "B.Paste" user)
		(5 "F.SilkS" user "F.Silkscreen")
		(7 "B.SilkS" user "B.Silkscreen")
		(1 "F.Mask" user)
		(3 "B.Mask" user)
		(17 "Dwgs.User" user "User.Drawings")
		(19 "Cmts.User" user "User.Comments")
		(21 "Eco1.User" user "User.Eco1")
		(23 "Eco2.User" user "User.Eco2")
		(25 "Edge.Cuts" user)
		(27 "Margin" user)
		(31 "F.CrtYd" user "F.Courtyard")
		(29 "B.CrtYd" user "B.Courtyard")
		(35 "F.Fab" user)
		(33 "B.Fab" user)
	)
	(footprint "antmicro-footprints:C_0402_1005Metric"
		(layer "B.Cu")
		(at 199.89 130.85 90)
		(descr "Capacitor SMD 0402")
		(tags "capacitor SMD 0402")
		(property "Reference" "C58"
			(at 8.025 -9.565 270)
			(layer "B.SilkS")
			(effects
				(font
					(size 0.7 0.7)
					(thickness 0.15)
				)
				(justify left bottom mirror)
			)
		)
		(property "Value" "C_10n_0402"
			(at -1.022927 -2.155213 270)
			(layer "B.Fab")
			(hide yes)
			(effects
				(font
					(size 0.7 0.7)
					(thickness 0.15)
				)
				(justify left bottom mirror)
			)
		)
		(property "Datasheet" "https://www.murata.com/products/productdetail?partno=GRM155R71H103KA88%23"
			(at 0 0 90)
			(layer "F.Fab")
			(hide yes)
			(effects
				(font
					(size 1.27 1.27)
					(thickness 0.15)
				)
			)
		)
		(property "Description" "SMD Multilayer Ceramic Capacitor, 10000 pF, 50 V, 0402 [1005 Metric], ± 10%, X7R, GRM Series"
			(at 0 0 90)
			(layer "F.Fab")
			(hide yes)
			(effects
				(font
					(size 1.27 1.27)
					(thickness 0.15)
				)
			)
		)
		(property "Author" "Antmicro"
			(at 330.74 -69.04 0)
			(layer "B.Fab")
			(hide yes)
			(effects
				(font
					(size 1 1)
					(thickness 0.15)
				)
				(justify mirror)
			)
		)
		(property "Dielectric" "X7R"
			(at 330.74 -69.04 0)
			(layer "B.Fab")
			(hide yes)
			(effects
				(font
					(size 1 1)
					(thickness 0.15)
				)
				(justify mirror)
			)
		)
		(property "License" "Apache-2.0"
			(at 330.74 -69.04 0)
			(layer "B.Fab")
			(hide yes)
			(effects
				(font
					(size 1 1)
					(thickness 0.15)
				)
				(justify mirror)
			)
		)
		(property "MPN" "GRM155R71H103KA88D"
			(at 330.74 -69.04 0)
			(layer "B.Fab")
			(hide yes)
			(effects
				(font
					(size 1 1)
					(thickness 0.15)
				)
				(justify mirror)
			)
		)
		(property "Manufacturer" "Murata"
			(at 330.74 -69.04 0)
			(layer "B.Fab")
			(hide yes)
			(effects
				(font
					(size 1 1)
					(thickness 0.15)
				)
				(justify mirror)
			)
		)
		(property "Public" ""
			(at 330.74 -69.04 0)
			(layer "B.Fab")
			(hide yes)
			(effects
				(font
					(size 1 1)
					(thickness 0.15)
				)
				(justify mirror)
			)
		)
		(property "Val" "10n"
			(at 330.74 -69.04 0)
			(layer "B.Fab")
			(hide yes)
			(effects
				(font
					(size 1 1)
					(thickness 0.15)
				)
				(justify mirror)
			)
		)
		(property "Voltage" "50V"
			(at 330.74 -69.04 0)
			(layer "B.Fab")
			(hide yes)
			(effects
				(font
					(size 1 1)
					(thickness 0.15)
				)
				(justify mirror)
			)
		)
		(sheetname "/FPGA Supply/")
		(sheetfile "fpga-supply.kicad_sch")
		(attr smd)
		(fp_rect
			(start -0.925 0.47)
			(end 0.925 -0.47)
			(stroke
				(width 0.05)
				(type default)
			)
			(fill no)
			(layer "B.CrtYd")
		)
		(fp_line
			(start 0.504 -0.248)
			(end -0.494 -0.248)
			(stroke
				(width 0.15)
				(type solid)
			)
			(layer "B.Fab")
		)
		(fp_line
			(start -0.494 -0.248)
			(end -0.494 0.25)
			(stroke
				(width 0.15)
				(type solid)
			)
			(layer "B.Fab")
		)
		(fp_line
			(start 0.504 0.25)
			(end 0.504 -0.248)
			(stroke
				(width 0.15)
				(type solid)
			)
			(layer "B.Fab")
		)
		(fp_line
			(start -0.494 0.25)
			(end 0.504 0.25)
			(stroke
				(width 0.15)
				(type solid)
			)
			(layer "B.Fab")
		)
		(fp_text user "License: Apache-2.0"
			(at -0.939 -5.799 270)
			(layer "B.Fab")
			(effects
				(font
					(size 0.7 0.7)
					(thickness 0.15)
				)
				(justify left bottom mirror)
			)
		)
		(fp_text user "Author: Antmicro"
			(at -0.939 -3.399 270)
			(layer "B.Fab")
			(effects
				(font
					(size 0.7 0.7)
					(thickness 0.15)
				)
				(justify left bottom mirror)
			)
		)
		(fp_text user "${REFERENCE}"
			(at -0.939 -4.599 270)
			(layer "B.Fab")
			(effects
				(font
					(size 0.7 0.7)
					(thickness 0.15)
				)
				(justify left bottom mirror)
			)
		)
		(pad "1" smd roundrect
			(at -0.48 0 90)
			(size 0.59 0.64)
			(layers "B.Cu" "B.Mask" "B.Paste")
			(roundrect_rratio 0.25)
			(net 417 "GND")
			(pintype "passive")
		)
		(pad "2" smd roundrect
			(at 0.48 0 90)
			(size 0.59 0.64)
			(layers "B.Cu" "B.Mask" "B.Paste")
			(roundrect_rratio 0.25)
			(net 49 "VDDAUX")
			(pintype "passive")
		)
	)
	(footprint "antmicro-footprints:TP_SMD_0.75mm"
		(layer "B.Cu")
		(at 185.4 146 180)
		(property "Reference" "TP22"
			(at 1.35 -1.475 45)
			(layer "B.SilkS")
			(hide yes)
			(effects
				(font
					(size 0.7 0.7)
					(thickness 0.15)
				)
				(justify left bottom mirror)
			)
		)
		(property "Value" "TP_0.75mm_SMD"
			(at 0 -1.2 0)
			(layer "B.Fab")
			(hide yes)
			(effects
				(font
					(size 0.7 0.7)
					(thickness 0.15)
				)
				(justify left bottom mirror)
			)
		)
		(property "Description" "SMT test point"
			(at 0 0 0)
			(layer "B.Fab")
			(hide yes)
			(effects
				(font
					(size 1.27 1.27)
					(thickness 0.15)
				)
				(justify mirror)
			)
		)
		(property "MPN" ""
			(at 0 0 0)
			(unlocked yes)
			(layer "B.Fab")
			(hide yes)
			(effects
				(font
					(size 1 1)
					(thickness 0.15)
				)
				(justify mirror)
			)
		)
		(property "Manufacturer" ""
			(at 0 0 0)
			(unlocked yes)
			(layer "B.Fab")
			(hide yes)
			(effects
				(font
					(size 1 1)
					(thickness 0.15)
				)
				(justify mirror)
			)
		)
		(property "Author" "Antmicro"
			(at 0 0 0)
			(unlocked yes)
			(layer "B.Fab")
			(hide yes)
			(effects
				(font
					(size 1 1)
					(thickness 0.15)
				)
				(justify mirror)
			)
		)
		(property "License" "Apache-2.0"
			(at 0 0 0)
			(unlocked yes)
			(layer "B.Fab")
			(hide yes)
			(effects
				(font
					(size 1 1)
					(thickness 0.15)
				)
				(justify mirror)
			)
		)
		(property "Public" "False"
			(at 0 0 0)
			(unlocked yes)
			(layer "B.Fab")
			(hide yes)
			(effects
				(font
					(size 1 1)
					(thickness 0.15)
				)
				(justify mirror)
			)
		)
		(sheetname "/Supply/")
		(sheetfile "supply.kicad_sch")
		(attr exclude_from_pos_files exclude_from_bom)
		(fp_circle
			(center 0 0)
			(end 0.475 0)
			(stroke
				(width 0.05)
				(type default)
			)
			(fill no)
			(layer "B.CrtYd")
		)
		(fp_text user "${REFERENCE}"
			(at -0.4 -2.7 0)
			(layer "B.Fab")
			(effects
				(font
					(size 0.7 0.7)
					(thickness 0.15)
				)
				(justify left bottom mirror)
			)
		)
		(fp_text user "Author: Antmicro"
			(at -0.4 -3.901 0)
			(layer "B.Fab")
			(effects
				(font
					(size 0.7 0.7)
					(thickness 0.15)
				)
				(justify left bottom mirror)
			)
		)
		(fp_text user "License: Apache-2.0"
			(at -0.4 -5.101 0)
			(layer "B.Fab")
			(effects
				(font
					(size 0.7 0.7)
					(thickness 0.15)
				)
				(justify left bottom mirror)
			)
		)
		(pad "1" smd circle
			(at 0 0 180)
			(size 0.75 0.75)
			(layers "B.Cu" "B.Mask")
			(net 634 "Net-(U7-OUT5)")
			(pinfunction "1")
			(pintype "passive")
		)
	)
	(footprint "antmicro-footprints:C_0402_1005Metric"
		(layer "B.Cu")
		(at 213.861 117.754 180)
		(descr "Capacitor SMD 0402")
		(tags "capacitor SMD 0402")
		(property "Reference" "C251"
			(at 24.711 -18.121 0)
			(layer "B.SilkS")
			(effects
				(font
					(size 0.7 0.7)
					(thickness 0.15)
				)
				(justify left bottom mirror)
			)
		)
		(property "Value" "C_1u_0402"
			(at -1.022927 -2.155213 0)
			(layer "B.Fab")
			(hide yes)
			(effects
				(font
					(size 0.7 0.7)
					(thickness 0.15)
				)
				(justify left bottom mirror)
			)
		)
		(property "Datasheet" "https://product.tdk.com/en/search/capacitor/ceramic/mlcc/info?part_no=C1005X6S1A105K050BC"
			(at 0 0 180)
			(layer "F.Fab")
			(hide yes)
			(effects
				(font
					(size 1.27 1.27)
					(thickness 0.15)
				)
			)
		)
		(property "Description" "SMD Multilayer Ceramic Capacitor, 1 µF, 10 V, 0402 [1005 Metric], ± 10%, X6S, C"
			(at 0 0 180)
			(layer "F.Fab")
			(hide yes)
			(effects
				(font
					(size 1.27 1.27)
					(thickness 0.15)
				)
			)
		)
		(property "Author" "Antmicro"
			(at 427.722 235.508 0)
			(layer "B.Fab")
			(hide yes)
			(effects
				(font
					(size 1 1)
					(thickness 0.15)
				)
				(justify mirror)
			)
		)
		(property "Dielectric" ""
			(at 427.722 235.508 0)
			(layer "B.Fab")
			(hide yes)
			(effects
				(font
					(size 1 1)
					(thickness 0.15)
				)
				(justify mirror)
			)
		)
		(property "License" "Apache-2.0"
			(at 427.722 235.508 0)
			(layer "B.Fab")
			(hide yes)
			(effects
				(font
					(size 1 1)
					(thickness 0.15)
				)
				(justify mirror)
			)
		)
		(property "MPN" "C1005X6S1A105K050BC"
			(at 427.722 235.508 0)
			(layer "B.Fab")
			(hide yes)
			(effects
				(font
					(size 1 1)
					(thickness 0.15)
				)
				(justify mirror)
			)
		)
		(property "Manufacturer" "TDK"
			(at 427.722 235.508 0)
			(layer "B.Fab")
			(hide yes)
			(effects
				(font
					(size 1 1)
					(thickness 0.15)
				)
				(justify mirror)
			)
		)
		(property "Public" ""
			(at 427.722 235.508 0)
			(layer "B.Fab")
			(hide yes)
			(effects
				(font
					(size 1 1)
					(thickness 0.15)
				)
				(justify mirror)
			)
		)
		(property "Val" "1u"
			(at 427.722 235.508 0)
			(layer "B.Fab")
			(hide yes)
			(effects
				(font
					(size 1 1)
					(thickness 0.15)
				)
				(justify mirror)
			)
		)
		(property "Voltage" ""
			(at 427.722 235.508 0)
			(layer "B.Fab")
			(hide yes)
			(effects
				(font
					(size 1 1)
					(thickness 0.15)
				)
				(justify mirror)
			)
		)
		(sheetname "/Ethernet/")
		(sheetfile "ethernet.kicad_sch")
		(attr smd)
		(fp_rect
			(start -0.925 0.47)
			(end 0.925 -0.47)
			(stroke
				(width 0.05)
				(type default)
			)
			(fill no)
			(layer "B.CrtYd")
		)
		(fp_line
			(start 0.504 0.25)
			(end 0.504 -0.248)
			(stroke
				(width 0.15)
				(type solid)
			)
			(layer "B.Fab")
		)
		(fp_line
			(start 0.504 -0.248)
			(end -0.494 -0.248)
			(stroke
				(width 0.15)
				(type solid)
			)
			(layer "B.Fab")
		)
		(fp_line
			(start -0.494 0.25)
			(end 0.504 0.25)
			(stroke
				(width 0.15)
				(type solid)
			)
			(layer "B.Fab")
		)
		(fp_line
			(start -0.494 -0.248)
			(end -0.494 0.25)
			(stroke
				(width 0.15)
				(type solid)
			)
			(layer "B.Fab")
		)
		(fp_text user "Author: Antmicro"
			(at -0.939 -3.399 0)
			(layer "B.Fab")
			(effects
				(font
					(size 0.7 0.7)
					(thickness 0.15)
				)
				(justify left bottom mirror)
			)
		)
		(fp_text user "${REFERENCE}"
			(at -0.939 -4.599 0)
			(layer "B.Fab")
			(effects
				(font
					(size 0.7 0.7)
					(thickness 0.15)
				)
				(justify left bottom mirror)
			)
		)
		(fp_text user "License: Apache-2.0"
			(at -0.939 -5.799 0)
			(layer "B.Fab")
			(effects
				(font
					(size 0.7 0.7)
					(thickness 0.15)
				)
				(justify left bottom mirror)
			)
		)
		(pad "1" smd roundrect
			(at -0.48 0 180)
			(size 0.59 0.64)
			(layers "B.Cu" "B.Mask" "B.Paste")
			(roundrect_rratio 0.25)
			(net 417 "GND")
			(pintype "passive")
		)
		(pad "2" smd roundrect
			(at 0.48 0 180)
			(size 0.59 0.64)
			(layers "B.Cu" "B.Mask" "B.Paste")
			(roundrect_rratio 0.25)
			(net 47 "+1V05")
			(pintype "passive")
		)
	)
	(footprint "antmicro-footprints:Fiducial_1mm_Mask2mm"
		(layer "B.Cu")
		(at 228.7 150.5 180)
		(descr "Circular Fiducial, 1mm bare copper, 3mm soldermask opening")
		(tags "fiducial")
		(property "Reference" "FD2"
			(at 0 1.4 0)
			(layer "B.SilkS")
			(hide yes)
			(effects
				(font
					(size 0.7 0.7)
					(thickness 0.15)
				)
				(justify left bottom mirror)
			)
		)
		(property "Value" "Fiducial_1mm_Mask2mm"
			(at 0 -2.2 0)
			(layer "B.Fab")
			(hide yes)
			(effects
				(font
					(size 0.7 0.7)
					(thickness 0.15)
				)
				(justify left bottom mirror)
			)
		)
		(property "Description" "Fiducial mask "
			(at 0 0 180)
			(layer "F.Fab")
			(hide yes)
			(effects
				(font
					(size 1.27 1.27)
					(thickness 0.15)
				)
			)
		)
		(property "Author" "Antmicro"
			(at 457.4 301 0)
			(layer "B.Fab")
			(hide yes)
			(effects
				(font
					(size 1 1)
					(thickness 0.15)
				)
				(justify mirror)
			)
		)
		(property "License" "Apache-2.0"
			(at 457.4 301 0)
			(layer "B.Fab")
			(hide yes)
			(effects
				(font
					(size 1 1)
					(thickness 0.15)
				)
				(justify mirror)
			)
		)
		(property "exclude_from_bom" ""
			(at 457.4 301 0)
			(layer "B.Fab")
			(hide yes)
			(effects
				(font
					(size 1 1)
					(thickness 0.15)
				)
				(justify mirror)
			)
		)
		(sheetfile "polarfire-som.kicad_sch")
		(attr board_only exclude_from_pos_files exclude_from_bom)
		(fp_circle
			(center 0 0)
			(end 1.24 0)
			(stroke
				(width 0.05)
				(type solid)
			)
			(fill no)
			(layer "B.CrtYd")
		)
		(fp_circle
			(center 0 0)
			(end 0.999 0)
			(stroke
				(width 0.15)
				(type solid)
			)
			(fill no)
			(layer "B.Fab")
		)
		(fp_text user "${REFERENCE}"
			(at -1.25 -4.603 0)
			(layer "B.Fab")
			(effects
				(font
					(size 0.7 0.7)
					(thickness 0.15)
				)
				(justify left bottom mirror)
			)
		)
		(fp_text user "Author: Antmicro"
			(at -1.25 -5.803 0)
			(layer "B.Fab")
			(effects
				(font
					(size 0.7 0.7)
					(thickness 0.15)
				)
				(justify left bottom mirror)
			)
		)
		(fp_text user "License: Apache-2.0"
			(at -1.25 -7.003 0)
			(layer "B.Fab")
			(effects
				(font
					(size 0.7 0.7)
					(thickness 0.15)
				)
				(justify left bottom mirror)
			)
		)
		(pad "" smd circle
			(at 0 0 180)
			(size 1 1)
			(layers "B.Cu" "B.Mask")
			(solder_mask_margin 0.5)
			(clearance 0.5)
		)
	)
	(footprint "antmicro-footprints:C_0402_1005Metric"
		(layer "B.Cu")
		(at 219.911 117.704)
		(descr "Capacitor SMD 0402")
		(tags "capacitor SMD 0402")
		(property "Reference" "C194"
			(at 6.539 4.446 0)
			(layer "B.SilkS")
			(effects
				(font
					(size 0.7 0.7)
					(thickness 0.15)
				)
				(justify right bottom mirror)
			)
		)
		(property "Value" "C_1u_0402"
			(at -1.022927 -2.155213 0)
			(layer "B.Fab")
			(hide yes)
			(effects
				(font
					(size 0.7 0.7)
					(thickness 0.15)
				)
				(justify right bottom mirror)
			)
		)
		(property "Datasheet" "https://product.tdk.com/en/search/capacitor/ceramic/mlcc/info?part_no=C1005X6S1A105K050BC"
			(at 0 0 0)
			(layer "F.Fab")
			(hide yes)
			(effects
				(font
					(size 1.27 1.27)
					(thickness 0.15)
				)
			)
		)
		(property "Description" "SMD Multilayer Ceramic Capacitor, 1 µF, 10 V, 0402 [1005 Metric], ± 10%, X6S, C"
			(at 0 0 0)
			(layer "F.Fab")
			(hide yes)
			(effects
				(font
					(size 1.27 1.27)
					(thickness 0.15)
				)
			)
		)
		(property "Author" "Antmicro"
			(at 0 0 0)
			(layer "B.Fab")
			(hide yes)
			(effects
				(font
					(size 1 1)
					(thickness 0.15)
				)
				(justify mirror)
			)
		)
		(property "Dielectric" ""
			(at 0 0 0)
			(layer "B.Fab")
			(hide yes)
			(effects
				(font
					(size 1 1)
					(thickness 0.15)
				)
				(justify mirror)
			)
		)
		(property "License" "Apache-2.0"
			(at 0 0 0)
			(layer "B.Fab")
			(hide yes)
			(effects
				(font
					(size 1 1)
					(thickness 0.15)
				)
				(justify mirror)
			)
		)
		(property "MPN" "C1005X6S1A105K050BC"
			(at 0 0 0)
			(layer "B.Fab")
			(hide yes)
			(effects
				(font
					(size 1 1)
					(thickness 0.15)
				)
				(justify mirror)
			)
		)
		(property "Manufacturer" "TDK"
			(at 0 0 0)
			(layer "B.Fab")
			(hide yes)
			(effects
				(font
					(size 1 1)
					(thickness 0.15)
				)
				(justify mirror)
			)
		)
		(property "Public" ""
			(at 0 0 0)
			(layer "B.Fab")
			(hide yes)
			(effects
				(font
					(size 1 1)
					(thickness 0.15)
				)
				(justify mirror)
			)
		)
		(property "Val" "1u"
			(at 0 0 0)
			(layer "B.Fab")
			(hide yes)
			(effects
				(font
					(size 1 1)
					(thickness 0.15)
				)
				(justify mirror)
			)
		)
		(property "Voltage" ""
			(at 0 0 0)
			(layer "B.Fab")
			(hide yes)
			(effects
				(font
					(size 1 1)
					(thickness 0.15)
				)
				(justify mirror)
			)
		)
		(sheetname "/Ethernet/")
		(sheetfile "ethernet.kicad_sch")
		(attr smd)
		(fp_rect
			(start -0.925 0.47)
			(end 0.925 -0.47)
			(stroke
				(width 0.05)
				(type default)
			)
			(fill no)
			(layer "B.CrtYd")
		)
		(fp_line
			(start -0.494 -0.248)
			(end -0.494 0.25)
			(stroke
				(width 0.15)
				(type solid)
			)
			(layer "B.Fab")
		)
		(fp_line
			(start -0.494 0.25)
			(end 0.504 0.25)
			(stroke
				(width 0.15)
				(type solid)
			)
			(layer "B.Fab")
		)
		(fp_line
			(start 0.504 -0.248)
			(end -0.494 -0.248)
			(stroke
				(width 0.15)
				(type solid)
			)
			(layer "B.Fab")
		)
		(fp_line
			(start 0.504 0.25)
			(end 0.504 -0.248)
			(stroke
				(width 0.15)
				(type solid)
			)
			(layer "B.Fab")
		)
		(fp_text user "Author: Antmicro"
			(at -0.939 -3.399 180)
			(layer "B.Fab")
			(effects
				(font
					(size 0.7 0.7)
					(thickness 0.15)
				)
				(justify left bottom mirror)
			)
		)
		(fp_text user "${REFERENCE}"
			(at -0.939 -4.599 180)
			(layer "B.Fab")
			(effects
				(font
					(size 0.7 0.7)
					(thickness 0.15)
				)
				(justify left bottom mirror)
			)
		)
		(fp_text user "License: Apache-2.0"
			(at -0.939 -5.799 180)
			(layer "B.Fab")
			(effects
				(font
					(size 0.7 0.7)
					(thickness 0.15)
				)
				(justify left bottom mirror)
			)
		)
		(pad "1" smd roundrect
			(at -0.48 0)
			(size 0.59 0.64)
			(layers "B.Cu" "B.Mask" "B.Paste")
			(roundrect_rratio 0.25)
			(net 417 "GND")
			(pintype "passive")
		)
		(pad "2" smd roundrect
			(at 0.48 0)
			(size 0.59 0.64)
			(layers "B.Cu" "B.Mask" "B.Paste")
			(roundrect_rratio 0.25)
			(net 418 "+2V5")
			(pintype "passive")
		)
	)
)
